# T6G (Grand Teton) — schematic netlist excerpt (pin names and nets, part order shuffled) for the footprints in the layout excerpt that follows; sources: Cadence DE-HDL packaged netlist, KiCad conversion of 04192023_DAF0TMB3IC0_F0TG_MB_C_brd_V02_OCP.brd

C6682  Q_CAP_DIFFBUS  DIFF BUS_0.22UF 6.3V 20% X6S  pkg C0201  page 330 : \1\ = P5E_CPU1_P1_TX_BUF_C_DN<10> ; \2\ = P5E_CPU1_P1_TX_BUF_DN<10>
R6233  Q_RES  10K 1% EMPTY  pkg 0402LF  page 267 : A = A_HSC_LOW ; B = GND
C6069  Q_CAP  0.001UF 50V 10% X7R  pkg C0402  page 177 : A = P1V2_AUX ; B = GND

(kicad_pcb
	(version 20260206)
	(generator "pcbnew")
	(generator_version "10.0")
	(general
		(thickness 1.6)
		(legacy_teardrops no)
	)
	(paper "A4")
	(title_block
		(title "04192023_DAF0TMB3IC0_F0TG_MB_C_brd_V02_OCP.brd")
		(comment 1 "Grand Teton / footprints 5119-5121 of 8354")
	)
	(layers
		(0 "F.Cu" signal "TOP")
		(4 "In1.Cu" signal "GND")
		(6 "In2.Cu" signal "IN1")
		(8 "In3.Cu" signal "GND1")
		(10 "In4.Cu" signal "IN2")
		(12 "In5.Cu" signal "GND2")
		(14 "In6.Cu" signal "IN3")
		(16 "In7.Cu" signal "GND3")
		(18 "In8.Cu" signal "VCC")
		(20 "In9.Cu" signal "VCC1")
		(22 "In10.Cu" signal "GND4")
		(24 "In11.Cu" signal "IN4")
		(26 "In12.Cu" signal "GND5")
		(28 "In13.Cu" signal "IN5")
		(30 "In14.Cu" signal "GND6")
		(32 "In15.Cu" signal "IN6")
		(34 "In16.Cu" signal "GND7")
		(2 "B.Cu" signal "BOTTOM")
		(9 "F.Adhes" user "F.Adhesive")
		(11 "B.Adhes" user "B.Adhesive")
		(13 "F.Paste" user "Package Geometry/Pastemask Top")
		(15 "B.Paste" user "Package Geometry/Pastemask Bottom")
		(5 "F.SilkS" user "Ref Des/Silkscreen Top")
		(7 "B.SilkS" user "Ref Des/Silkscreen Bottom")
		(1 "F.Mask" user "Board Geometry/Soldermask Top")
		(3 "B.Mask" user "Board Geometry/Soldermask Bottom")
		(17 "Dwgs.User" user "User.Drawings")
		(19 "Cmts.User" user "User.Comments")
		(21 "Eco1.User" user "User.Eco1")
		(23 "Eco2.User" user "User.Eco2")
		(25 "Edge.Cuts" user "Board Geometry/Outline")
		(27 "Margin" user)
		(31 "F.CrtYd" user "Package Geometry/Place Bound Top")
		(29 "B.CrtYd" user "Package Geometry/Place Bound Bottom")
		(35 "F.Fab" user "Ref Des/Assembly Top")
		(33 "B.Fab" user "Ref Des/Assembly Bottom")
	)
	(footprint ""
		(layer "B.Cu")
		(at 79.932784 -408.517344 90)
		(property "Reference" "C6682"
			(at 0 0 90)
			(layer "B.SilkS")
			(hide yes)
			(effects
				(font
					(size 1.27 1.27)
				)
				(justify mirror)
			)
		)
		(property "Value" ""
			(at 0 0 90)
			(layer "B.Fab")
			(effects
				(font
					(size 1.27 1.27)
				)
				(justify mirror)
			)
		)
		(duplicate_pad_numbers_are_jumpers no)
		(fp_line
			(start 0.299974 -0.150114)
			(end -0.299974 -0.150114)
			(stroke
				(width 0.1)
				(type default)
			)
			(layer "B.Fab")
		)
		(fp_line
			(start -0.299974 -0.150114)
			(end -0.299974 0.150114)
			(stroke
				(width 0.1)
				(type default)
			)
			(layer "B.Fab")
		)
		(fp_line
			(start 0.299974 0.150114)
			(end 0.299974 -0.150114)
			(stroke
				(width 0.1)
				(type default)
			)
			(layer "B.Fab")
		)
		(fp_line
			(start -0.299974 0.150114)
			(end 0.299974 0.150114)
			(stroke
				(width 0.1)
				(type default)
			)
			(layer "B.Fab")
		)
		(pad "1" smd rect
			(at 0.2667 0 270)
			(size 0.3048 0.381)
			(layers "B.Cu" "B.Mask" "B.Paste")
			(net "P5E_CPU1_P1_TX_BUF_C_DN<10>")
		)
		(pad "2" smd rect
			(at -0.2667 0 270)
			(size 0.3048 0.381)
			(layers "B.Cu" "B.Mask" "B.Paste")
			(net "P5E_CPU1_P1_TX_BUF_DN<10>")
		)
	)
	(footprint ""
		(layer "B.Cu")
		(at 138.65352 -41.781222 180)
		(property "Reference" "C6069"
			(at 0 0 0)
			(layer "B.SilkS")
			(hide yes)
			(effects
				(font
					(size 1.27 1.27)
				)
				(justify mirror)
			)
		)
		(property "Value" ""
			(at 0 0 0)
			(layer "B.Fab")
			(effects
				(font
					(size 1.27 1.27)
				)
				(justify mirror)
			)
		)
		(duplicate_pad_numbers_are_jumpers no)
		(fp_line
			(start 0.7874 0.4064)
			(end 0.7874 -0.4064)
			(stroke
				(width 0.1524)
				(type default)
			)
			(layer "B.SilkS")
		)
		(fp_line
			(start 0.7874 -0.4064)
			(end -0.7874 -0.4064)
			(stroke
				(width 0.1524)
				(type default)
			)
			(layer "B.SilkS")
		)
		(fp_line
			(start -0.7874 0.4064)
			(end 0.7874 0.4064)
			(stroke
				(width 0.1524)
				(type default)
			)
			(layer "B.SilkS")
		)
		(fp_line
			(start -0.7874 -0.4064)
			(end -0.7874 0.4064)
			(stroke
				(width 0.1524)
				(type default)
			)
			(layer "B.SilkS")
		)
		(fp_line
			(start 0.67945 0.3048)
			(end 0.67945 -0.305054)
			(stroke
				(width 0.1)
				(type default)
			)
			(layer "B.Fab")
		)
		(fp_line
			(start 0.67945 -0.305054)
			(end 0.12065 -0.305054)
			(stroke
				(width 0.1)
				(type default)
			)
			(layer "B.Fab")
		)
		(fp_line
			(start 0.12065 0.3048)
			(end 0.67945 0.3048)
			(stroke
				(width 0.1)
				(type default)
			)
			(layer "B.Fab")
		)
		(fp_line
			(start 0.12065 0.2794)
			(end 0.12065 0.3048)
			(stroke
				(width 0.1)
				(type default)
			)
			(layer "B.Fab")
		)
		(fp_line
			(start 0.12065 -0.2794)
			(end -0.12065 -0.2794)
			(stroke
				(width 0.1)
				(type default)
			)
			(layer "B.Fab")
		)
		(fp_line
			(start 0.12065 -0.305054)
			(end 0.12065 -0.2794)
			(stroke
				(width 0.1)
				(type default)
			)
			(layer "B.Fab")
		)
		(fp_line
			(start -0.120396 0.3048)
			(end -0.120396 0.2794)
			(stroke
				(width 0.1)
				(type default)
			)
			(layer "B.Fab")
		)
		(fp_line
			(start -0.120396 0.2794)
			(end 0.12065 0.2794)
			(stroke
				(width 0.1)
				(type default)
			)
			(layer "B.Fab")
		)
		(fp_line
			(start -0.12065 -0.2794)
			(end -0.12065 -0.3048)
			(stroke
				(width 0.1)
				(type default)
			)
			(layer "B.Fab")
		)
		(fp_line
			(start -0.12065 -0.3048)
			(end -0.67945 -0.3048)
			(stroke
				(width 0.1)
				(type default)
			)
			(layer "B.Fab")
		)
		(fp_line
			(start -0.67945 0.3048)
			(end -0.120396 0.3048)
			(stroke
				(width 0.1)
				(type default)
			)
			(layer "B.Fab")
		)
		(fp_line
			(start -0.67945 -0.3048)
			(end -0.67945 0.3048)
			(stroke
				(width 0.1)
				(type default)
			)
			(layer "B.Fab")
		)
		(pad "1" smd circle
			(at 0.40005 0)
			(size 0 0)
			(layers "B.Cu" "B.Mask" "B.Paste")
			(net "P1V2_AUX")
		)
		(pad "2" smd circle
			(at -0.40005 0)
			(size 0 0)
			(layers "B.Cu" "B.Mask" "B.Paste")
			(net "GND")
		)
	)
	(footprint ""
		(layer "B.Cu")
		(at 181.845458 -426.898816 -90)
		(property "Reference" "R6233"
			(at 0 0 90)
			(layer "B.SilkS")
			(hide yes)
			(effects
				(font
					(size 1.27 1.27)
				)
				(justify mirror)
			)
		)
		(property "Value" ""
			(at 0 0 90)
			(layer "B.Fab")
			(effects
				(font
					(size 1.27 1.27)
				)
				(justify mirror)
			)
		)
		(duplicate_pad_numbers_are_jumpers no)
		(fp_line
			(start -0.7874 0.4064)
			(end 0.7874 0.4064)
			(stroke
				(width 0.1524)
				(type default)
			)
			(layer "B.SilkS")
		)
		(fp_line
			(start 0.7874 0.4064)
			(end 0.7874 -0.4064)
			(stroke
				(width 0.1524)
				(type default)
			)
			(layer "B.SilkS")
		)
		(fp_line
			(start -0.7874 -0.4064)
			(end -0.7874 0.4064)
			(stroke
				(width 0.1524)
				(type default)
			)
			(layer "B.SilkS")
		)
		(fp_line
			(start 0.7874 -0.4064)
			(end -0.7874 -0.4064)
			(stroke
				(width 0.1524)
				(type default)
			)
			(layer "B.SilkS")
		)
		(fp_line
			(start -0.67945 0.3048)
			(end -0.120396 0.3048)
			(stroke
				(width 0.1)
				(type default)
			)
			(layer "B.Fab")
		)
		(fp_line
			(start -0.120396 0.3048)
			(end -0.120396 0.2794)
			(stroke
				(width 0.1)
				(type default)
			)
			(layer "B.Fab")
		)
		(fp_line
			(start 0.12065 0.3048)
			(end 0.67945 0.3048)
			(stroke
				(width 0.1)
				(type default)
			)
			(layer "B.Fab")
		)
		(fp_line
			(start 0.67945 0.3048)
			(end 0.67945 -0.305054)
			(stroke
				(width 0.1)
				(type default)
			)
			(layer "B.Fab")
		)
		(fp_line
			(start -0.120396 0.2794)
			(end 0.12065 0.2794)
			(stroke
				(width 0.1)
				(type default)
			)
			(layer "B.Fab")
		)
		(fp_line
			(start 0.12065 0.2794)
			(end 0.12065 0.3048)
			(stroke
				(width 0.1)
				(type default)
			)
			(layer "B.Fab")
		)
		(fp_line
			(start -0.12065 -0.2794)
			(end -0.12065 -0.3048)
			(stroke
				(width 0.1)
				(type default)
			)
			(layer "B.Fab")
		)
		(fp_line
			(start 0.12065 -0.2794)
			(end -0.12065 -0.2794)
			(stroke
				(width 0.1)
				(type default)
			)
			(layer "B.Fab")
		)
		(fp_line
			(start -0.67945 -0.3048)
			(end -0.67945 0.3048)
			(stroke
				(width 0.1)
				(type default)
			)
			(layer "B.Fab")
		)
		(fp_line
			(start -0.12065 -0.3048)
			(end -0.67945 -0.3048)
			(stroke
				(width 0.1)
				(type default)
			)
			(layer "B.Fab")
		)
		(fp_line
			(start 0.12065 -0.305054)
			(end 0.12065 -0.2794)
			(stroke
				(width 0.1)
				(type default)
			)
			(layer "B.Fab")
		)
		(fp_line
			(start 0.67945 -0.305054)
			(end 0.12065 -0.305054)
			(stroke
				(width 0.1)
				(type default)
			)
			(layer "B.Fab")
		)
		(pad "1" smd circle
			(at 0.40005 0 90)
			(size 0 0)
			(layers "B.Cu" "B.Mask" "B.Paste")
			(net "A_HSC_LOW")
		)
		(pad "2" smd circle
			(at -0.40005 0 90)
			(size 0 0)
			(layers "B.Cu" "B.Mask" "B.Paste")
			(net "GND")
		)
	)
)
